(kicad_pcb
	(version 20241229)
	(generator "pcbnew")
	(generator_version "9.0")
	(general
		(thickness 1.62)
		(legacy_teardrops no)
	)
	(paper "A4")
	(title_block
		(title "OCuLink to 10GbE adapter")
		(date "2026-02-23")
		(rev "1.1.0")
		(company "Antmicro Ltd")
		(comment 1 "www.antmicro.com")
		(comment 9 "footprints 297-300 of 510")
	)
	(layers
		(0 "F.Cu" signal)
		(4 "In1.Cu" signal)
		(6 "In2.Cu" signal)
		(8 "In3.Cu" signal)
		(10 "In4.Cu" signal)
		(12 "In5.Cu" signal)
		(14 "In6.Cu" signal)
		(2 "B.Cu" signal)
		(9 "F.Adhes" user "F.Adhesive")
		(11 "B.Adhes" user "B.Adhesive")
		(13 "F.Paste" user)
		(15 "B.Paste" user)
		(5 "F.SilkS" user "F.Silkscreen")
		(7 "B.SilkS" user "B.Silkscreen")
		(1 "F.Mask" user)
		(3 "B.Mask" user)
		(17 "Dwgs.User" user "User.Drawings")
		(19 "Cmts.User" user "User.Comments")
		(21 "Eco1.User" user "User.Eco1")
		(23 "Eco2.User" user "User.Eco2")
		(25 "Edge.Cuts" user)
		(27 "Margin" user)
		(31 "F.CrtYd" user "F.Courtyard")
		(29 "B.CrtYd" user "B.Courtyard")
		(35 "F.Fab" user)
		(33 "B.Fab" user)
	)
	(footprint "antmicro-footprints:R_0402_1005Metric"
		(layer "B.Cu")
		(at 91.7 103.45 180)
		(descr "Resistor SMD 0402")
		(tags "resistor SMD 0402")
		(property "Reference" "R77"
			(at -2.95 -0.42 0)
			(layer "B.SilkS")
			(effects
				(font
					(size 0.7 0.7)
					(thickness 0.15)
				)
				(justify left bottom mirror)
			)
		)
		(property "Value" "R_100R_0402"
			(at -1.011843 -1.772046 0)
			(layer "B.Fab")
			(hide yes)
			(effects
				(font
					(size 0.7 0.7)
					(thickness 0.15)
				)
				(justify left bottom mirror)
			)
		)
		(property "Datasheet" "https://www.bourns.com/docs/product-datasheets/cr.pdf"
			(at 0 0 0)
			(layer "B.Fab")
			(hide yes)
			(effects
				(font
					(size 1.27 1.27)
					(thickness 0.15)
				)
				(justify mirror)
			)
		)
		(property "Description" "SMD Chip Resistor, 100 ohm, ± 1%, 62.5 mW, 0402 [1005 Metric], Thick Film, General Purpose"
			(at 0 0 0)
			(layer "B.Fab")
			(hide yes)
			(effects
				(font
					(size 1.27 1.27)
					(thickness 0.15)
				)
				(justify mirror)
			)
		)
		(property "MPN" "CR0402-FX-1000GLF"
			(at 0 0 180)
			(unlocked yes)
			(layer "B.Fab")
			(hide yes)
			(effects
				(font
					(size 1 1)
					(thickness 0.15)
				)
				(justify mirror)
			)
		)
		(property "Manufacturer" "Bourns"
			(at 0 0 180)
			(unlocked yes)
			(layer "B.Fab")
			(hide yes)
			(effects
				(font
					(size 1 1)
					(thickness 0.15)
				)
				(justify mirror)
			)
		)
		(property "License" "Apache-2.0"
			(at 0 0 180)
			(unlocked yes)
			(layer "B.Fab")
			(hide yes)
			(effects
				(font
					(size 1 1)
					(thickness 0.15)
				)
				(justify mirror)
			)
		)
		(property "Author" "Antmicro"
			(at 0 0 180)
			(unlocked yes)
			(layer "B.Fab")
			(hide yes)
			(effects
				(font
					(size 1 1)
					(thickness 0.15)
				)
				(justify mirror)
			)
		)
		(property "Val" "100R"
			(at 0 0 180)
			(unlocked yes)
			(layer "B.Fab")
			(hide yes)
			(effects
				(font
					(size 1 1)
					(thickness 0.15)
				)
				(justify mirror)
			)
		)
		(property "Tolerance" "1%"
			(at 0 0 180)
			(unlocked yes)
			(layer "B.Fab")
			(hide yes)
			(effects
				(font
					(size 1 1)
					(thickness 0.15)
				)
				(justify mirror)
			)
		)
		(sheetname "/X710-AT2 10GbE/")
		(sheetfile "x710-at2-10gbe.kicad_sch")
		(attr smd exclude_from_pos_files exclude_from_bom dnp)
		(fp_rect
			(start -0.925 0.47)
			(end 0.925 -0.47)
			(stroke
				(width 0.05)
				(type default)
			)
			(fill no)
			(layer "B.CrtYd")
		)
		(fp_rect
			(start -0.5 0.25)
			(end 0.5 -0.25)
			(stroke
				(width 0.15)
				(type solid)
			)
			(fill no)
			(layer "B.Fab")
		)
		(pad "1" smd roundrect
			(at -0.48 0 180)
			(size 0.59 0.64)
			(layers "B.Cu" "B.Mask" "B.Paste")
			(roundrect_rratio 0.25)
			(net 28 "GND")
			(pintype "passive")
		)
		(pad "2" smd roundrect
			(at 0.48 0 180)
			(size 0.59 0.64)
			(layers "B.Cu" "B.Mask" "B.Paste")
			(roundrect_rratio 0.25)
			(net 85 "/X710-AT2 10GbE/OSC_SEL")
			(pintype "passive")
		)
	)
	(footprint "antmicro-footprints:C_0402_1005Metric"
		(layer "B.Cu")
		(at 79.55 97.4 90)
		(descr "Capacitor SMD 0402")
		(tags "capacitor SMD 0402")
		(property "Reference" "C137"
			(at 1.02 -0.28 90)
			(layer "B.SilkS")
			(effects
				(font
					(size 0.7 0.7)
					(thickness 0.15)
				)
				(justify right top mirror)
			)
		)
		(property "Value" "C_1u_25V_0402"
			(at -1.022927 -2.155213 90)
			(layer "B.Fab")
			(hide yes)
			(effects
				(font
					(size 0.7 0.7)
					(thickness 0.15)
				)
				(justify right top mirror)
			)
		)
		(property "Datasheet" "https://www.murata.com/products/productdetail?partno=GRM155R61E105KE11%23"
			(at 0 0 90)
			(layer "B.Fab")
			(hide yes)
			(effects
				(font
					(size 1.27 1.27)
					(thickness 0.15)
				)
				(justify mirror)
			)
		)
		(property "Description" "SMD Multilayer Ceramic Capacitor, 1 µF, 25 V, 0402 [1005 Metric], ± 10%, X5R, GRM Series"
			(at 0 0 90)
			(layer "B.Fab")
			(hide yes)
			(effects
				(font
					(size 1.27 1.27)
					(thickness 0.15)
				)
				(justify mirror)
			)
		)
		(property "MPN" "GRM155R61E105KE11J"
			(at 0 0 90)
			(unlocked yes)
			(layer "B.Fab")
			(hide yes)
			(effects
				(font
					(size 1 1)
					(thickness 0.15)
				)
				(justify mirror)
			)
		)
		(property "Manufacturer" "Murata"
			(at 0 0 90)
			(unlocked yes)
			(layer "B.Fab")
			(hide yes)
			(effects
				(font
					(size 1 1)
					(thickness 0.15)
				)
				(justify mirror)
			)
		)
		(property "License" "Apache-2.0"
			(at 0 0 90)
			(unlocked yes)
			(layer "B.Fab")
			(hide yes)
			(effects
				(font
					(size 1 1)
					(thickness 0.15)
				)
				(justify mirror)
			)
		)
		(property "Author" "Antmicro"
			(at 0 0 90)
			(unlocked yes)
			(layer "B.Fab")
			(hide yes)
			(effects
				(font
					(size 1 1)
					(thickness 0.15)
				)
				(justify mirror)
			)
		)
		(property "Val" "1u"
			(at 0 0 90)
			(unlocked yes)
			(layer "B.Fab")
			(hide yes)
			(effects
				(font
					(size 1 1)
					(thickness 0.15)
				)
				(justify mirror)
			)
		)
		(property "Voltage" "25V"
			(at 0 0 90)
			(unlocked yes)
			(layer "B.Fab")
			(hide yes)
			(effects
				(font
					(size 1 1)
					(thickness 0.15)
				)
				(justify mirror)
			)
		)
		(property "Dielectric" "X5R"
			(at 0 0 90)
			(unlocked yes)
			(layer "B.Fab")
			(hide yes)
			(effects
				(font
					(size 1 1)
					(thickness 0.15)
				)
				(justify mirror)
			)
		)
		(sheetname "/X710-AT2 power/")
		(sheetfile "x710-at2-power.kicad_sch")
		(attr smd)
		(fp_rect
			(start -0.925 0.47)
			(end 0.925 -0.47)
			(stroke
				(width 0.05)
				(type default)
			)
			(fill no)
			(layer "B.CrtYd")
		)
		(fp_line
			(start 0.504 -0.248)
			(end -0.494 -0.248)
			(stroke
				(width 0.15)
				(type solid)
			)
			(layer "B.Fab")
		)
		(fp_line
			(start -0.494 -0.248)
			(end -0.494 0.25)
			(stroke
				(width 0.15)
				(type solid)
			)
			(layer "B.Fab")
		)
		(fp_line
			(start 0.504 0.25)
			(end 0.504 -0.248)
			(stroke
				(width 0.15)
				(type solid)
			)
			(layer "B.Fab")
		)
		(fp_line
			(start -0.494 0.25)
			(end 0.504 0.25)
			(stroke
				(width 0.15)
				(type solid)
			)
			(layer "B.Fab")
		)
		(pad "1" smd roundrect
			(at -0.48 0 90)
			(size 0.59 0.64)
			(layers "B.Cu" "B.Mask" "B.Paste")
			(roundrect_rratio 0.25)
			(net 28 "GND")
			(pintype "passive")
		)
		(pad "2" smd roundrect
			(at 0.48 0 90)
			(size 0.59 0.64)
			(layers "B.Cu" "B.Mask" "B.Paste")
			(roundrect_rratio 0.25)
			(net 7 "+3V3")
			(pintype "passive")
		)
	)
	(footprint "antmicro-footprints:C_0402_1005Metric"
		(layer "B.Cu")
		(at 76.95 100.35 180)
		(descr "Capacitor SMD 0402")
		(tags "capacitor SMD 0402")
		(property "Reference" "C101"
			(at -0.85 -0.45 0)
			(layer "B.SilkS")
			(effects
				(font
					(size 0.7 0.7)
					(thickness 0.15)
				)
				(justify right bottom mirror)
			)
		)
		(property "Value" "C_1u_25V_0402"
			(at -1.022927 -2.155213 0)
			(layer "B.Fab")
			(hide yes)
			(effects
				(font
					(size 0.7 0.7)
					(thickness 0.15)
				)
				(justify left bottom mirror)
			)
		)
		(property "Datasheet" "https://www.murata.com/products/productdetail?partno=GRM155R61E105KE11%23"
			(at 0 0 0)
			(layer "B.Fab")
			(hide yes)
			(effects
				(font
					(size 1.27 1.27)
					(thickness 0.15)
				)
				(justify mirror)
			)
		)
		(property "Description" "SMD Multilayer Ceramic Capacitor, 1 µF, 25 V, 0402 [1005 Metric], ± 10%, X5R, GRM Series"
			(at 0 0 0)
			(layer "B.Fab")
			(hide yes)
			(effects
				(font
					(size 1.27 1.27)
					(thickness 0.15)
				)
				(justify mirror)
			)
		)
		(property "MPN" "GRM155R61E105KE11J"
			(at 0 0 180)
			(unlocked yes)
			(layer "B.Fab")
			(hide yes)
			(effects
				(font
					(size 1 1)
					(thickness 0.15)
				)
				(justify mirror)
			)
		)
		(property "Manufacturer" "Murata"
			(at 0 0 180)
			(unlocked yes)
			(layer "B.Fab")
			(hide yes)
			(effects
				(font
					(size 1 1)
					(thickness 0.15)
				)
				(justify mirror)
			)
		)
		(property "License" "Apache-2.0"
			(at 0 0 180)
			(unlocked yes)
			(layer "B.Fab")
			(hide yes)
			(effects
				(font
					(size 1 1)
					(thickness 0.15)
				)
				(justify mirror)
			)
		)
		(property "Author" "Antmicro"
			(at 0 0 180)
			(unlocked yes)
			(layer "B.Fab")
			(hide yes)
			(effects
				(font
					(size 1 1)
					(thickness 0.15)
				)
				(justify mirror)
			)
		)
		(property "Val" "1u"
			(at 0 0 180)
			(unlocked yes)
			(layer "B.Fab")
			(hide yes)
			(effects
				(font
					(size 1 1)
					(thickness 0.15)
				)
				(justify mirror)
			)
		)
		(property "Voltage" "25V"
			(at 0 0 180)
			(unlocked yes)
			(layer "B.Fab")
			(hide yes)
			(effects
				(font
					(size 1 1)
					(thickness 0.15)
				)
				(justify mirror)
			)
		)
		(property "Dielectric" "X5R"
			(at 0 0 180)
			(unlocked yes)
			(layer "B.Fab")
			(hide yes)
			(effects
				(font
					(size 1 1)
					(thickness 0.15)
				)
				(justify mirror)
			)
		)
		(sheetname "/X710-AT2 power/")
		(sheetfile "x710-at2-power.kicad_sch")
		(attr smd)
		(fp_rect
			(start -0.925 0.47)
			(end 0.925 -0.47)
			(stroke
				(width 0.05)
				(type default)
			)
			(fill no)
			(layer "B.CrtYd")
		)
		(fp_line
			(start 0.504 0.25)
			(end 0.504 -0.248)
			(stroke
				(width 0.15)
				(type solid)
			)
			(layer "B.Fab")
		)
		(fp_line
			(start 0.504 -0.248)
			(end -0.494 -0.248)
			(stroke
				(width 0.15)
				(type solid)
			)
			(layer "B.Fab")
		)
		(fp_line
			(start -0.494 0.25)
			(end 0.504 0.25)
			(stroke
				(width 0.15)
				(type solid)
			)
			(layer "B.Fab")
		)
		(fp_line
			(start -0.494 -0.248)
			(end -0.494 0.25)
			(stroke
				(width 0.15)
				(type solid)
			)
			(layer "B.Fab")
		)
		(pad "1" smd roundrect
			(at -0.48 0 180)
			(size 0.59 0.64)
			(layers "B.Cu" "B.Mask" "B.Paste")
			(roundrect_rratio 0.25)
			(net 28 "GND")
			(pintype "passive")
		)
		(pad "2" smd roundrect
			(at 0.48 0 180)
			(size 0.59 0.64)
			(layers "B.Cu" "B.Mask" "B.Paste")
			(roundrect_rratio 0.25)
			(net 18 "+1V88")
			(pintype "passive")
		)
	)
	(footprint "antmicro-footprints:R_0402_1005Metric"
		(layer "B.Cu")
		(at 83.3 102 -90)
		(descr "Resistor SMD 0402")
		(tags "resistor SMD 0402")
		(property "Reference" "R121"
			(at -11.92 -0.3 90)
			(layer "B.SilkS")
			(effects
				(font
					(size 0.7 0.7)
					(thickness 0.15)
				)
				(justify left bottom mirror)
			)
		)
		(property "Value" "R_1k_0402"
			(at -1.011843 -1.772046 90)
			(layer "B.Fab")
			(hide yes)
			(effects
				(font
					(size 0.7 0.7)
					(thickness 0.15)
				)
				(justify left bottom mirror)
			)
		)
		(property "Datasheet" "https://www.bourns.com/docs/product-datasheets/cr.pdf"
			(at 0 0 90)
			(layer "B.Fab")
			(hide yes)
			(effects
				(font
					(size 1.27 1.27)
					(thickness 0.15)
				)
				(justify mirror)
			)
		)
		(property "Description" "SMD Chip Resistor, 1 kohm, ± 1%, 63 mW, 0402 [1005 Metric], Thick Film, General Purpose"
			(at 0 0 90)
			(layer "B.Fab")
			(hide yes)
			(effects
				(font
					(size 1.27 1.27)
					(thickness 0.15)
				)
				(justify mirror)
			)
		)
		(property "MPN" "CR0402-FX-1001GLF"
			(at 0 0 270)
			(unlocked yes)
			(layer "B.Fab")
			(hide yes)
			(effects
				(font
					(size 1 1)
					(thickness 0.15)
				)
				(justify mirror)
			)
		)
		(property "Manufacturer" "Bourns"
			(at 0 0 270)
			(unlocked yes)
			(layer "B.Fab")
			(hide yes)
			(effects
				(font
					(size 1 1)
					(thickness 0.15)
				)
				(justify mirror)
			)
		)
		(property "License" "Apache-2.0"
			(at 0 0 270)
			(unlocked yes)
			(layer "B.Fab")
			(hide yes)
			(effects
				(font
					(size 1 1)
					(thickness 0.15)
				)
				(justify mirror)
			)
		)
		(property "Author" "Antmicro"
			(at 0 0 270)
			(unlocked yes)
			(layer "B.Fab")
			(hide yes)
			(effects
				(font
					(size 1 1)
					(thickness 0.15)
				)
				(justify mirror)
			)
		)
		(property "Val" "1k"
			(at 0 0 270)
			(unlocked yes)
			(layer "B.Fab")
			(hide yes)
			(effects
				(font
					(size 1 1)
					(thickness 0.15)
				)
				(justify mirror)
			)
		)
		(property "Tolerance" "1%"
			(at 0 0 270)
			(unlocked yes)
			(layer "B.Fab")
			(hide yes)
			(effects
				(font
					(size 1 1)
					(thickness 0.15)
				)
				(justify mirror)
			)
		)
		(sheetname "/X710-AT2 Misc/")
		(sheetfile "x710-at2-mics.kicad_sch")
		(attr smd)
		(fp_rect
			(start -0.925 0.47)
			(end 0.925 -0.47)
			(stroke
				(width 0.05)
				(type default)
			)
			(fill no)
			(layer "B.CrtYd")
		)
		(fp_rect
			(start -0.5 0.25)
			(end 0.5 -0.25)
			(stroke
				(width 0.15)
				(type solid)
			)
			(fill no)
			(layer "B.Fab")
		)
		(pad "1" smd roundrect
			(at -0.48 0 270)
			(size 0.59 0.64)
			(layers "B.Cu" "B.Mask" "B.Paste")
			(roundrect_rratio 0.25)
			(net 28 "GND")
			(pintype "passive")
		)
		(pad "2" smd roundrect
			(at 0.48 0 270)
			(size 0.59 0.64)
			(layers "B.Cu" "B.Mask" "B.Paste")
			(roundrect_rratio 0.25)
			(net 116 "/X710-AT2 Misc/~{PHY_TRST}")
			(pintype "passive")
		)
	)
)
